(kicad_pcb
	(version 20260206)
	(generator "pcbnew")
	(generator_version "10.0")
	(general
		(thickness 1.6)
		(legacy_teardrops no)
	)
	(paper "A4")
	(title_block
		(title "baseboard — 13948-1b.1110WZS1818.brd")
		(comment 1 "Honey Badger (Wiwynn) / footprints 1822-1829 of 2523")
	)
	(layers
		(0 "F.Cu" signal "TOP")
		(4 "In1.Cu" signal "L2GND")
		(6 "In2.Cu" signal "L3")
		(8 "In3.Cu" signal "L4VCC")
		(10 "In4.Cu" signal "L5VCC")
		(12 "In5.Cu" signal "L6")
		(14 "In6.Cu" signal "L7GND")
		(2 "B.Cu" signal "BOTTOM")
		(9 "F.Adhes" user "F.Adhesive")
		(11 "B.Adhes" user "B.Adhesive")
		(13 "F.Paste" user "Package Geometry/Pastemask Top")
		(15 "B.Paste" user "Package Geometry/Pastemask Bottom")
		(5 "F.SilkS" user "Ref Des/Silkscreen Top")
		(7 "B.SilkS" user "Ref Des/Silkscreen Bottom")
		(1 "F.Mask" user "Board Geometry/Soldermask Top")
		(3 "B.Mask" user "Board Geometry/Soldermask Bottom")
		(17 "Dwgs.User" user "User.Drawings")
		(19 "Cmts.User" user "User.Comments")
		(21 "Eco1.User" user "User.Eco1")
		(23 "Eco2.User" user "User.Eco2")
		(25 "Edge.Cuts" user "Board Geometry/Outline")
		(27 "Margin" user)
		(31 "F.CrtYd" user "Package Geometry/Place Bound Top")
		(29 "B.CrtYd" user "Package Geometry/Place Bound Bottom")
		(35 "F.Fab" user "Ref Des/Assembly Top")
		(33 "B.Fab" user "Ref Des/Assembly Bottom")
	)
	(footprint ""
		(layer "B.Cu")
		(at 94.358206 -54.71668 90)
		(property "Reference" "SC980"
			(at 0 0 90)
			(layer "B.SilkS")
			(hide yes)
			(effects
				(font
					(size 1.27 1.27)
				)
				(justify mirror)
			)
		)
		(property "Value" "SCD1U16V2KX-3GP"
			(at -1.1811 -2.7051 90)
			(unlocked yes)
			(layer "B.Fab")
			(hide yes)
			(effects
				(font
					(size 1.016 1.016)
					(thickness 0.1524)
				)
				(justify mirror)
			)
		)
		(property "Device Type" "C402H22"
			(at -1.1811 -4.2291 90)
			(unlocked yes)
			(layer "B.Fab")
			(hide yes)
			(effects
				(font
					(size 1.016 1.016)
					(thickness 0.1524)
				)
				(justify mirror)
			)
		)
		(duplicate_pad_numbers_are_jumpers no)
		(fp_rect
			(start 0.4318 0.9525)
			(end -0.4318 -0.9525)
			(stroke
				(width 0)
				(type default)
			)
			(fill no)
			(layer "B.CrtYd")
		)
		(fp_rect
			(start 0.4318 0.9525)
			(end -0.4318 -0.9525)
			(stroke
				(width 0)
				(type default)
			)
			(fill no)
			(layer "B.Fab")
		)
		(pad "1" smd custom
			(at 0 -0.4445 270)
			(size 0.1524 0.1524)
			(layers "B.Cu" "B.Mask" "B.Paste")
			(net "P1V8_C")
			(options
				(clearance outline)
				(anchor circle)
			)
			(primitives
				(gr_poly
					(pts
						(arc
							(start 0.3048 0.2032)
							(mid 0.275042 0.275042)
							(end 0.2032 0.3048)
						)
						(arc
							(start -0.2032 0.3048)
							(mid -0.275042 0.275042)
							(end -0.3048 0.2032)
						)
						(arc
							(start -0.3048 -0.2032)
							(mid -0.275042 -0.275042)
							(end -0.2032 -0.3048)
						)
						(arc
							(start 0.2032 -0.3048)
							(mid 0.275042 -0.275042)
							(end 0.3048 -0.2032)
						)
					)
					(width 0)
					(fill yes)
				)
			)
		)
		(pad "2" smd custom
			(at 0 0.4445 270)
			(size 0.1524 0.1524)
			(layers "B.Cu" "B.Mask" "B.Paste")
			(net "GND")
			(options
				(clearance outline)
				(anchor circle)
			)
			(primitives
				(gr_poly
					(pts
						(arc
							(start 0.3048 0.2032)
							(mid 0.275042 0.275042)
							(end 0.2032 0.3048)
						)
						(arc
							(start -0.2032 0.3048)
							(mid -0.275042 0.275042)
							(end -0.3048 0.2032)
						)
						(arc
							(start -0.3048 -0.2032)
							(mid -0.275042 -0.275042)
							(end -0.2032 -0.3048)
						)
						(arc
							(start 0.2032 -0.3048)
							(mid 0.275042 -0.275042)
							(end 0.3048 -0.2032)
						)
					)
					(width 0)
					(fill yes)
				)
			)
		)
	)
	(footprint ""
		(layer "B.Cu")
		(at 311.702958 -51.308 180)
		(property "Reference" "C276"
			(at 0 0 0)
			(layer "B.SilkS")
			(hide yes)
			(effects
				(font
					(size 1.27 1.27)
				)
				(justify mirror)
			)
		)
		(property "Value" "SC22U25V5MX-GP"
			(at 0.0762 -6.1214 180)
			(unlocked yes)
			(layer "B.Fab")
			(hide yes)
			(effects
				(font
					(size 1.016 1.016)
					(thickness 0.1524)
				)
				(justify mirror)
			)
		)
		(property "Device Type" "C805H58"
			(at 0.0762 -8.1534 180)
			(unlocked yes)
			(layer "B.Fab")
			(hide yes)
			(effects
				(font
					(size 1.016 1.016)
					(thickness 0.1524)
				)
				(justify mirror)
			)
		)
		(duplicate_pad_numbers_are_jumpers no)
		(fp_line
			(start -0.635 0)
			(end 0.635 0)
			(stroke
				(width 0.508)
				(type default)
			)
			(layer "B.SilkS")
		)
		(fp_rect
			(start 0.9652 1.778)
			(end -0.9652 -1.778)
			(stroke
				(width 0)
				(type default)
			)
			(fill no)
			(layer "B.CrtYd")
		)
		(fp_poly
			(pts
				(xy 0.9652 -1.778) (xy -0.9652 -1.778) (xy -0.9652 1.778) (xy 0.9652 1.778)
			)
			(stroke
				(width 0)
				(type default)
			)
			(fill no)
			(layer "B.Fab")
		)
		(pad "1" smd rect
			(at 0 -0.9652)
			(size 1.397 1.143)
			(layers "B.Cu" "B.Mask" "B.Paste")
			(net "P12V")
		)
		(pad "2" smd rect
			(at 0 0.9652)
			(size 1.397 1.143)
			(layers "B.Cu" "B.Mask" "B.Paste")
			(net "GND")
		)
	)
	(footprint ""
		(layer "B.Cu")
		(at 109.671612 -205.867)
		(property "Reference" "SR893"
			(at 0 0 0)
			(layer "B.SilkS")
			(hide yes)
			(effects
				(font
					(size 1.27 1.27)
				)
				(justify mirror)
			)
		)
		(property "Value" "0R2J-2-GP"
			(at -0.064008 -3.993896 0)
			(unlocked yes)
			(layer "B.Fab")
			(hide yes)
			(effects
				(font
					(size 1.016 1.016)
					(thickness 0.1524)
				)
				(justify mirror)
			)
		)
		(property "Device Type" "R402H16"
			(at -0.064008 -5.517896 0)
			(unlocked yes)
			(layer "B.Fab")
			(hide yes)
			(effects
				(font
					(size 1.016 1.016)
					(thickness 0.1524)
				)
				(justify mirror)
			)
		)
		(duplicate_pad_numbers_are_jumpers no)
		(fp_line
			(start -0.508 -0.9398)
			(end 0.508 -0.9398)
			(stroke
				(width 0.1524)
				(type default)
			)
			(layer "B.SilkS")
		)
		(fp_line
			(start 0.508 -0.9398)
			(end 0.508 0.9398)
			(stroke
				(width 0.1524)
				(type default)
			)
			(layer "B.SilkS")
		)
		(fp_rect
			(start 0.508 0.9398)
			(end -0.508 -0.9398)
			(stroke
				(width 0)
				(type default)
			)
			(fill no)
			(layer "B.CrtYd")
		)
		(fp_rect
			(start 0.508 0.9398)
			(end -0.508 -0.9398)
			(stroke
				(width 0)
				(type default)
			)
			(fill no)
			(layer "B.Fab")
		)
		(pad "1" smd custom
			(at 0 -0.4445 180)
			(size 0.1397 0.1397)
			(layers "B.Cu" "B.Mask" "B.Paste")
			(net "SAS_HDD_REDV_SER_RX8_P")
			(options
				(clearance outline)
				(anchor circle)
			)
			(primitives
				(gr_poly
					(pts
						(arc
							(start -0.1778 0.2794)
							(mid -0.249642 0.249642)
							(end -0.2794 0.1778)
						)
						(arc
							(start -0.2794 -0.1778)
							(mid -0.249642 -0.249642)
							(end -0.1778 -0.2794)
						)
						(arc
							(start 0.1778 -0.2794)
							(mid 0.249642 -0.249642)
							(end 0.2794 -0.1778)
						)
						(arc
							(start 0.2794 0.1778)
							(mid 0.249642 0.249642)
							(end 0.1778 0.2794)
						)
					)
					(width 0)
					(fill yes)
				)
			)
		)
		(pad "2" smd custom
			(at 0 0.4445 180)
			(size 0.1397 0.1397)
			(layers "B.Cu" "B.Mask" "B.Paste")
			(net "SAS_HDD_CONN_RX8_P")
			(options
				(clearance outline)
				(anchor circle)
			)
			(primitives
				(gr_poly
					(pts
						(arc
							(start -0.1778 0.2794)
							(mid -0.249642 0.249642)
							(end -0.2794 0.1778)
						)
						(arc
							(start -0.2794 -0.1778)
							(mid -0.249642 -0.249642)
							(end -0.1778 -0.2794)
						)
						(arc
							(start 0.1778 -0.2794)
							(mid 0.249642 -0.249642)
							(end 0.2794 -0.1778)
						)
						(arc
							(start 0.2794 0.1778)
							(mid 0.249642 0.249642)
							(end 0.1778 0.2794)
						)
					)
					(width 0)
					(fill yes)
				)
			)
		)
	)
	(footprint ""
		(layer "B.Cu")
		(at 119.234966 -30.988 -90)
		(property "Reference" "SR643"
			(at 0 0 90)
			(layer "B.SilkS")
			(hide yes)
			(effects
				(font
					(size 1.27 1.27)
				)
				(justify mirror)
			)
		)
		(property "Value" "4K7R2F-GP"
			(at -0.064008 -3.993896 270)
			(unlocked yes)
			(layer "B.Fab")
			(hide yes)
			(effects
				(font
					(size 1.016 1.016)
					(thickness 0.1524)
				)
				(justify mirror)
			)
		)
		(property "Device Type" "R402H16"
			(at -0.064008 -5.517896 270)
			(unlocked yes)
			(layer "B.Fab")
			(hide yes)
			(effects
				(font
					(size 1.016 1.016)
					(thickness 0.1524)
				)
				(justify mirror)
			)
		)
		(duplicate_pad_numbers_are_jumpers no)
		(fp_line
			(start -0.508 -0.9398)
			(end 0.508 -0.9398)
			(stroke
				(width 0.1524)
				(type default)
			)
			(layer "B.SilkS")
		)
		(fp_line
			(start 0.508 -0.9398)
			(end 0.508 0.9398)
			(stroke
				(width 0.1524)
				(type default)
			)
			(layer "B.SilkS")
		)
		(fp_rect
			(start 0.508 0.9398)
			(end -0.508 -0.9398)
			(stroke
				(width 0)
				(type default)
			)
			(fill no)
			(layer "B.CrtYd")
		)
		(fp_rect
			(start 0.508 0.9398)
			(end -0.508 -0.9398)
			(stroke
				(width 0)
				(type default)
			)
			(fill no)
			(layer "B.Fab")
		)
		(pad "1" smd custom
			(at 0 -0.4445 90)
			(size 0.1397 0.1397)
			(layers "B.Cu" "B.Mask" "B.Paste")
			(net "P1V8_C")
			(options
				(clearance outline)
				(anchor circle)
			)
			(primitives
				(gr_poly
					(pts
						(arc
							(start -0.1778 0.2794)
							(mid -0.249642 0.249642)
							(end -0.2794 0.1778)
						)
						(arc
							(start -0.2794 -0.1778)
							(mid -0.249642 -0.249642)
							(end -0.1778 -0.2794)
						)
						(arc
							(start 0.1778 -0.2794)
							(mid 0.249642 -0.249642)
							(end 0.2794 -0.1778)
						)
						(arc
							(start 0.2794 0.1778)
							(mid 0.249642 0.249642)
							(end 0.1778 0.2794)
						)
					)
					(width 0)
					(fill yes)
				)
			)
		)
		(pad "2" smd custom
			(at 0 0.4445 90)
			(size 0.1397 0.1397)
			(layers "B.Cu" "B.Mask" "B.Paste")
			(net "UART_SERCLK")
			(options
				(clearance outline)
				(anchor circle)
			)
			(primitives
				(gr_poly
					(pts
						(arc
							(start -0.1778 0.2794)
							(mid -0.249642 0.249642)
							(end -0.2794 0.1778)
						)
						(arc
							(start -0.2794 -0.1778)
							(mid -0.249642 -0.249642)
							(end -0.1778 -0.2794)
						)
						(arc
							(start 0.1778 -0.2794)
							(mid 0.249642 -0.249642)
							(end 0.2794 -0.1778)
						)
						(arc
							(start 0.2794 0.1778)
							(mid 0.249642 0.249642)
							(end 0.1778 0.2794)
						)
					)
					(width 0)
					(fill yes)
				)
			)
		)
	)
	(footprint ""
		(layer "B.Cu")
		(at 90.30716 -37.084 90)
		(property "Reference" "SC937"
			(at 0 0 90)
			(layer "B.SilkS")
			(hide yes)
			(effects
				(font
					(size 1.27 1.27)
				)
				(justify mirror)
			)
		)
		(property "Value" "SC1U6D3V1MX-GP"
			(at -1.9177 2.0193 90)
			(unlocked yes)
			(layer "B.Fab")
			(hide yes)
			(effects
				(font
					(size 1.016 1.016)
					(thickness 0.1524)
				)
				(justify mirror)
			)
		)
		(property "Device Type" "C0201H14"
			(at -1.9177 0.4953 90)
			(unlocked yes)
			(layer "B.Fab")
			(hide yes)
			(effects
				(font
					(size 1.016 1.016)
					(thickness 0.1524)
				)
				(justify mirror)
			)
		)
		(duplicate_pad_numbers_are_jumpers no)
		(fp_rect
			(start 0.1524 0.3048)
			(end -0.1524 -0.3048)
			(stroke
				(width 0)
				(type default)
			)
			(fill no)
			(layer "B.CrtYd")
		)
		(fp_poly
			(pts
				(xy 0.2794 0.6477) (xy 0.2794 -0.6477) (xy -0.2794 -0.6477) (xy -0.2794 -0.1905) (xy -0.1524 -0.1905)
				(xy -0.1524 -0.3048) (xy 0.1524 -0.3048) (xy 0.1524 0.3048) (xy -0.1524 0.3048) (xy -0.1524 -0.1778)
				(xy -0.2794 -0.1778) (xy -0.2794 0.6477)
			)
			(stroke
				(width 0)
				(type default)
			)
			(fill no)
			(layer "B.CrtYd")
		)
		(fp_rect
			(start 0.2794 0.6477)
			(end -0.2794 -0.6477)
			(stroke
				(width 0)
				(type default)
			)
			(fill no)
			(layer "B.Fab")
		)
		(pad "1" smd custom
			(at 0 -0.2794 270)
			(size 0.0762 0.0762)
			(layers "B.Cu" "B.Mask" "B.Paste")
			(net "SAS0_VDDH")
			(options
				(clearance outline)
				(anchor circle)
			)
			(primitives
				(gr_poly
					(pts
						(arc
							(start 0.1524 0.127)
							(mid 0.137521 0.162921)
							(end 0.1016 0.1778)
						)
						(arc
							(start -0.1016 0.1778)
							(mid -0.137521 0.162921)
							(end -0.1524 0.127)
						)
						(arc
							(start -0.1524 -0.127)
							(mid -0.137521 -0.162921)
							(end -0.1016 -0.1778)
						)
						(arc
							(start 0.1016 -0.1778)
							(mid 0.137521 -0.162921)
							(end 0.1524 -0.127)
						)
					)
					(width 0)
					(fill yes)
				)
			)
		)
		(pad "2" smd custom
			(at 0 0.2794 270)
			(size 0.0762 0.0762)
			(layers "B.Cu" "B.Mask" "B.Paste")
			(net "GND")
			(options
				(clearance outline)
				(anchor circle)
			)
			(primitives
				(gr_poly
					(pts
						(arc
							(start 0.1524 0.127)
							(mid 0.137521 0.162921)
							(end 0.1016 0.1778)
						)
						(arc
							(start -0.1016 0.1778)
							(mid -0.137521 0.162921)
							(end -0.1524 0.127)
						)
						(arc
							(start -0.1524 -0.127)
							(mid -0.137521 -0.162921)
							(end -0.1016 -0.1778)
						)
						(arc
							(start 0.1016 -0.1778)
							(mid 0.137521 -0.162921)
							(end 0.1524 -0.127)
						)
					)
					(width 0)
					(fill yes)
				)
			)
		)
	)
	(footprint ""
		(layer "B.Cu")
		(at 305.91506 -179.3748 180)
		(property "Reference" "C192"
			(at 0 0 0)
			(layer "B.SilkS")
			(hide yes)
			(effects
				(font
					(size 1.27 1.27)
				)
				(justify mirror)
			)
		)
		(property "Value" "SC1U6D3V3KX-2GP"
			(at 0 -2.8194 180)
			(unlocked yes)
			(layer "B.Fab")
			(hide yes)
			(effects
				(font
					(size 1.016 1.016)
					(thickness 0.1524)
				)
				(justify mirror)
			)
		)
		(property "Device Type" "C603H36"
			(at 0 -4.3434 180)
			(unlocked yes)
			(layer "B.Fab")
			(hide yes)
			(effects
				(font
					(size 1.016 1.016)
					(thickness 0.1524)
				)
				(justify mirror)
			)
		)
		(duplicate_pad_numbers_are_jumpers no)
		(fp_line
			(start -0.508 0)
			(end 0.508 0)
			(stroke
				(width 0.2032)
				(type default)
			)
			(layer "B.SilkS")
		)
		(fp_rect
			(start 0.5842 1.3335)
			(end -0.5842 -1.3335)
			(stroke
				(width 0)
				(type default)
			)
			(fill no)
			(layer "B.CrtYd")
		)
		(fp_rect
			(start 0.5842 1.3335)
			(end -0.5842 -1.3335)
			(stroke
				(width 0)
				(type default)
			)
			(fill no)
			(layer "B.Fab")
		)
		(pad "1" smd custom
			(at 0 -0.762)
			(size 0.2159 0.2159)
			(layers "B.Cu" "B.Mask" "B.Paste")
			(net "ADCAV33")
			(options
				(clearance outline)
				(anchor circle)
			)
			(primitives
				(gr_poly
					(pts
						(arc
							(start -0.3302 0.4318)
							(mid -0.402042 0.402042)
							(end -0.4318 0.3302)
						)
						(arc
							(start -0.4318 -0.3302)
							(mid -0.402042 -0.402042)
							(end -0.3302 -0.4318)
						)
						(arc
							(start 0.3302 -0.4318)
							(mid 0.402042 -0.402042)
							(end 0.4318 -0.3302)
						)
						(arc
							(start 0.4318 0.3302)
							(mid 0.402042 0.402042)
							(end 0.3302 0.4318)
						)
					)
					(width 0)
					(fill yes)
				)
			)
		)
		(pad "2" smd custom
			(at 0 0.762)
			(size 0.2159 0.2159)
			(layers "B.Cu" "B.Mask" "B.Paste")
			(net "GND")
			(options
				(clearance outline)
				(anchor circle)
			)
			(primitives
				(gr_poly
					(pts
						(arc
							(start -0.3302 0.4318)
							(mid -0.402042 0.402042)
							(end -0.4318 0.3302)
						)
						(arc
							(start -0.4318 -0.3302)
							(mid -0.402042 -0.402042)
							(end -0.3302 -0.4318)
						)
						(arc
							(start 0.3302 -0.4318)
							(mid 0.402042 -0.402042)
							(end 0.4318 -0.3302)
						)
						(arc
							(start 0.4318 0.3302)
							(mid 0.402042 0.402042)
							(end 0.3302 0.4318)
						)
					)
					(width 0)
					(fill yes)
				)
			)
		)
	)
	(footprint ""
		(layer "B.Cu")
		(at 324.358 -184.404 180)
		(property "Reference" "R3100"
			(at 0 0 0)
			(layer "B.SilkS")
			(hide yes)
			(effects
				(font
					(size 1.27 1.27)
				)
				(justify mirror)
			)
		)
		(property "Value" "1KR2F-3-GP"
			(at -0.064008 -3.993896 180)
			(unlocked yes)
			(layer "B.Fab")
			(hide yes)
			(effects
				(font
					(size 1.016 1.016)
					(thickness 0.1524)
				)
				(justify mirror)
			)
		)
		(property "Device Type" "R402H16"
			(at -0.064008 -5.517896 180)
			(unlocked yes)
			(layer "B.Fab")
			(hide yes)
			(effects
				(font
					(size 1.016 1.016)
					(thickness 0.1524)
				)
				(justify mirror)
			)
		)
		(duplicate_pad_numbers_are_jumpers no)
		(fp_line
			(start 0.508 -0.9398)
			(end 0.508 0.9398)
			(stroke
				(width 0.1524)
				(type default)
			)
			(layer "B.SilkS")
		)
		(fp_line
			(start -0.508 -0.9398)
			(end 0.508 -0.9398)
			(stroke
				(width 0.1524)
				(type default)
			)
			(layer "B.SilkS")
		)
		(fp_rect
			(start 0.508 0.9398)
			(end -0.508 -0.9398)
			(stroke
				(width 0)
				(type default)
			)
			(fill no)
			(layer "B.CrtYd")
		)
		(fp_rect
			(start 0.508 0.9398)
			(end -0.508 -0.9398)
			(stroke
				(width 0)
				(type default)
			)
			(fill no)
			(layer "B.Fab")
		)
		(pad "1" smd custom
			(at 0 -0.4445)
			(size 0.1397 0.1397)
			(layers "B.Cu" "B.Mask" "B.Paste")
			(net "ADC_P0V9_E")
			(options
				(clearance outline)
				(anchor circle)
			)
			(primitives
				(gr_poly
					(pts
						(arc
							(start -0.1778 0.2794)
							(mid -0.249642 0.249642)
							(end -0.2794 0.1778)
						)
						(arc
							(start -0.2794 -0.1778)
							(mid -0.249642 -0.249642)
							(end -0.1778 -0.2794)
						)
						(arc
							(start 0.1778 -0.2794)
							(mid 0.249642 -0.249642)
							(end 0.2794 -0.1778)
						)
						(arc
							(start 0.2794 0.1778)
							(mid 0.249642 0.249642)
							(end 0.1778 0.2794)
						)
					)
					(width 0)
					(fill yes)
				)
			)
		)
		(pad "2" smd custom
			(at 0 0.4445)
			(size 0.1397 0.1397)
			(layers "B.Cu" "B.Mask" "B.Paste")
			(net "GND")
			(options
				(clearance outline)
				(anchor circle)
			)
			(primitives
				(gr_poly
					(pts
						(arc
							(start -0.1778 0.2794)
							(mid -0.249642 0.249642)
							(end -0.2794 0.1778)
						)
						(arc
							(start -0.2794 -0.1778)
							(mid -0.249642 -0.249642)
							(end -0.1778 -0.2794)
						)
						(arc
							(start 0.1778 -0.2794)
							(mid 0.249642 -0.249642)
							(end 0.2794 -0.1778)
						)
						(arc
							(start 0.2794 0.1778)
							(mid 0.249642 0.249642)
							(end 0.1778 0.2794)
						)
					)
					(width 0)
					(fill yes)
				)
			)
		)
	)
	(footprint ""
		(layer "B.Cu")
		(at 100.870766 -37.719 90)
		(property "Reference" "SC942"
			(at 0 0 90)
			(layer "B.SilkS")
			(hide yes)
			(effects
				(font
					(size 1.27 1.27)
				)
				(justify mirror)
			)
		)
		(property "Value" "SCD1U6D3V1KX-GP"
			(at 2.8321 -1.7399 90)
			(unlocked yes)
			(layer "B.Fab")
			(hide yes)
			(effects
				(font
					(size 1.016 1.016)
					(thickness 0.1524)
				)
				(justify mirror)
			)
		)
		(property "Device Type" "C0201H13"
			(at 2.8321 -3.2639 90)
			(unlocked yes)
			(layer "B.Fab")
			(hide yes)
			(effects
				(font
					(size 1.016 1.016)
					(thickness 0.1524)
				)
				(justify mirror)
			)
		)
		(duplicate_pad_numbers_are_jumpers no)
		(fp_rect
			(start 0.2794 0.6477)
			(end -0.2794 -0.6477)
			(stroke
				(width 0)
				(type default)
			)
			(fill no)
			(layer "B.CrtYd")
		)
		(fp_rect
			(start 0.2794 0.6477)
			(end -0.2794 -0.6477)
			(stroke
				(width 0)
				(type default)
			)
			(fill no)
			(layer "B.Fab")
		)
		(pad "1" smd custom
			(at 0 -0.2794 270)
			(size 0.0762 0.0762)
			(layers "B.Cu" "B.Mask" "B.Paste")
			(net "P1V5_C")
			(options
				(clearance outline)
				(anchor circle)
			)
			(primitives
				(gr_poly
					(pts
						(arc
							(start 0.1524 0.127)
							(mid 0.137521 0.162921)
							(end 0.1016 0.1778)
						)
						(arc
							(start -0.1016 0.1778)
							(mid -0.137521 0.162921)
							(end -0.1524 0.127)
						)
						(arc
							(start -0.1524 -0.127)
							(mid -0.137521 -0.162921)
							(end -0.1016 -0.1778)
						)
						(arc
							(start 0.1016 -0.1778)
							(mid 0.137521 -0.162921)
							(end 0.1524 -0.127)
						)
					)
					(width 0)
					(fill yes)
				)
			)
		)
		(pad "2" smd custom
			(at 0 0.2794 270)
			(size 0.0762 0.0762)
			(layers "B.Cu" "B.Mask" "B.Paste")
			(net "GND")
			(options
				(clearance outline)
				(anchor circle)
			)
			(primitives
				(gr_poly
					(pts
						(arc
							(start 0.1524 0.127)
							(mid 0.137521 0.162921)
							(end 0.1016 0.1778)
						)
						(arc
							(start -0.1016 0.1778)
							(mid -0.137521 0.162921)
							(end -0.1524 0.127)
						)
						(arc
							(start -0.1524 -0.127)
							(mid -0.137521 -0.162921)
							(end -0.1016 -0.1778)
						)
						(arc
							(start 0.1016 -0.1778)
							(mid 0.137521 -0.162921)
							(end 0.1524 -0.127)
						)
					)
					(width 0)
					(fill yes)
				)
			)
		)
	)
)
